(kicad_pcb
	(version 20260206)
	(generator "pcbnew")
	(generator_version "10.0")
	(general
		(thickness 1.6)
		(legacy_teardrops no)
	)
	(paper "A4")
	(title_block
		(title "Bryce Canyon_SCC_16316-1_OCP.brd")
		(comment 1 "Bryce Canyon / footprints 1251-1257 of 1561")
	)
	(layers
		(0 "F.Cu" signal "TOP")
		(4 "In1.Cu" signal "L2GND")
		(6 "In2.Cu" signal "L3")
		(8 "In3.Cu" signal "L4VCC")
		(10 "In4.Cu" signal "L5VCC")
		(12 "In5.Cu" signal "L6")
		(14 "In6.Cu" signal "L7GND")
		(2 "B.Cu" signal "BOTTOM")
		(9 "F.Adhes" user "F.Adhesive")
		(11 "B.Adhes" user "B.Adhesive")
		(13 "F.Paste" user "Package Geometry/Pastemask Top")
		(15 "B.Paste" user "Package Geometry/Pastemask Bottom")
		(5 "F.SilkS" user "Ref Des/Silkscreen Top")
		(7 "B.SilkS" user "Ref Des/Silkscreen Bottom")
		(1 "F.Mask" user "Board Geometry/Soldermask Top")
		(3 "B.Mask" user "Board Geometry/Soldermask Bottom")
		(17 "Dwgs.User" user "User.Drawings")
		(19 "Cmts.User" user "User.Comments")
		(21 "Eco1.User" user "User.Eco1")
		(23 "Eco2.User" user "User.Eco2")
		(25 "Edge.Cuts" user "Board Geometry/Outline")
		(27 "Margin" user)
		(31 "F.CrtYd" user "Package Geometry/Place Bound Top")
		(29 "B.CrtYd" user "Package Geometry/Place Bound Bottom")
		(35 "F.Fab" user "Ref Des/Assembly Top")
		(33 "B.Fab" user "Ref Des/Assembly Bottom")
	)
	(footprint ""
		(layer "B.Cu")
		(at 201.295 -41.148)
		(property "Reference" "U15"
			(at 0 0 0)
			(layer "B.SilkS")
			(hide yes)
			(effects
				(font
					(size 1.27 1.27)
				)
				(justify mirror)
			)
		)
		(property "Value" "CAT24C64WI-GT3-GP"
			(at 3.707384 -1.5367 0)
			(unlocked yes)
			(layer "B.Fab")
			(hide yes)
			(effects
				(font
					(size 1.016 1.016)
					(thickness 0.1524)
				)
				(justify mirror)
			)
		)
		(property "Device Type" "SOIC8H69"
			(at 3.707384 -3.0607 0)
			(unlocked yes)
			(layer "B.Fab")
			(hide yes)
			(effects
				(font
					(size 1.016 1.016)
					(thickness 0.1524)
				)
				(justify mirror)
			)
		)
		(duplicate_pad_numbers_are_jumpers no)
		(fp_line
			(start -2.1336 -1.4224)
			(end 2.7432 -1.4224)
			(stroke
				(width 0.1524)
				(type default)
			)
			(layer "B.SilkS")
		)
		(fp_line
			(start -2.1336 1.4224)
			(end -2.1336 -1.4224)
			(stroke
				(width 0.1524)
				(type default)
			)
			(layer "B.SilkS")
		)
		(fp_line
			(start 2.1844 -0.0508)
			(end 2.7178 0.508)
			(stroke
				(width 0.1524)
				(type default)
			)
			(layer "B.SilkS")
		)
		(fp_line
			(start 2.6289 3.4417)
			(end 2.6289 1.4732)
			(stroke
				(width 0.381)
				(type default)
			)
			(layer "B.SilkS")
		)
		(fp_line
			(start 2.7178 -0.508)
			(end 2.1844 -0.0508)
			(stroke
				(width 0.1524)
				(type default)
			)
			(layer "B.SilkS")
		)
		(fp_line
			(start 2.7432 -1.4224)
			(end 2.7432 1.4224)
			(stroke
				(width 0.1524)
				(type default)
			)
			(layer "B.SilkS")
		)
		(fp_line
			(start 2.7432 1.4224)
			(end -2.1336 1.4224)
			(stroke
				(width 0.1524)
				(type default)
			)
			(layer "B.SilkS")
		)
		(fp_line
			(start 2.7432 1.4224)
			(end 2.6416 1.4224)
			(stroke
				(width 0.1524)
				(type default)
			)
			(layer "B.SilkS")
		)
		(fp_poly
			(pts
				(xy 2.2098 -1.4224) (xy 2.2098 1.4224) (xy -2.2098 1.4224) (xy -2.2098 -1.4224)
			)
			(stroke
				(width 0)
				(type default)
			)
			(fill yes)
			(layer "B.SilkS")
		)
		(fp_rect
			(start 2.450084 2.999994)
			(end -2.450084 -2.999994)
			(stroke
				(width 0)
				(type default)
			)
			(fill no)
			(layer "B.CrtYd")
		)
		(fp_poly
			(pts
				(xy 2.8194 3.6322) (xy 2.8194 -3.6322) (xy -2.8194 -3.6322) (xy -2.8194 1.18364) (xy -2.450084 1.18364)
				(xy -2.450084 -2.999994) (xy 2.450084 -2.999994) (xy 2.450084 2.999994) (xy -2.450084 2.999994)
				(xy -2.450084 1.18618) (xy -2.8194 1.18618) (xy -2.8194 3.6322)
			)
			(stroke
				(width 0)
				(type default)
			)
			(fill no)
			(layer "B.CrtYd")
		)
		(fp_rect
			(start 2.8194 3.6322)
			(end -2.8194 -3.6322)
			(stroke
				(width 0)
				(type default)
			)
			(fill no)
			(layer "B.Fab")
		)
		(pad "1" smd rect
			(at 1.905 2.54 180)
			(size 0.635 1.651)
			(layers "B.Cu" "B.Mask" "B.Paste")
			(net "IOC_EEPROM_A0")
		)
		(pad "2" smd rect
			(at 0.635 2.54 180)
			(size 0.635 1.651)
			(layers "B.Cu" "B.Mask" "B.Paste")
			(net "IOC_EEPROM_A1")
		)
		(pad "3" smd rect
			(at -0.635 2.54 180)
			(size 0.635 1.651)
			(layers "B.Cu" "B.Mask" "B.Paste")
			(net "IOC_EEPROM_A2")
		)
		(pad "4" smd rect
			(at -1.905 2.54 180)
			(size 0.635 1.651)
			(layers "B.Cu" "B.Mask" "B.Paste")
			(net "GND")
		)
		(pad "5" smd rect
			(at -1.905 -2.54 180)
			(size 0.635 1.651)
			(layers "B.Cu" "B.Mask" "B.Paste")
			(net "IOC_EEPROM_SDA")
		)
		(pad "6" smd rect
			(at -0.635 -2.54 180)
			(size 0.635 1.651)
			(layers "B.Cu" "B.Mask" "B.Paste")
			(net "IOC_EEPROM_SCL")
		)
		(pad "7" smd rect
			(at 0.635 -2.54 180)
			(size 0.635 1.651)
			(layers "B.Cu" "B.Mask" "B.Paste")
			(net "IOC_EEPROM_WP")
		)
		(pad "8" smd rect
			(at 1.905 -2.54 180)
			(size 0.635 1.651)
			(layers "B.Cu" "B.Mask" "B.Paste")
			(net "P1V8_C")
		)
	)
	(footprint ""
		(layer "B.Cu")
		(at 183.144668 -44.78401 -90)
		(property "Reference" "C479"
			(at 0 0 90)
			(layer "B.SilkS")
			(hide yes)
			(effects
				(font
					(size 1.27 1.27)
				)
				(justify mirror)
			)
		)
		(property "Value" "SCD1U6D3V1KX-GP"
			(at 2.8321 -1.7399 270)
			(unlocked yes)
			(layer "B.Fab")
			(hide yes)
			(effects
				(font
					(size 1.016 1.016)
					(thickness 0.1524)
				)
				(justify mirror)
			)
		)
		(property "Device Type" "C0201H13"
			(at 2.8321 -3.2639 270)
			(unlocked yes)
			(layer "B.Fab")
			(hide yes)
			(effects
				(font
					(size 1.016 1.016)
					(thickness 0.1524)
				)
				(justify mirror)
			)
		)
		(duplicate_pad_numbers_are_jumpers no)
		(fp_rect
			(start 0.2794 0.6477)
			(end -0.2794 -0.6477)
			(stroke
				(width 0)
				(type default)
			)
			(fill no)
			(layer "B.CrtYd")
		)
		(fp_rect
			(start 0.2794 0.6477)
			(end -0.2794 -0.6477)
			(stroke
				(width 0)
				(type default)
			)
			(fill no)
			(layer "B.Fab")
		)
		(pad "1" smd custom
			(at 0 -0.2794 90)
			(size 0.0762 0.0762)
			(layers "B.Cu" "B.Mask" "B.Paste")
			(net "P1V8_C")
			(options
				(clearance outline)
				(anchor circle)
			)
			(primitives
				(gr_poly
					(pts
						(arc
							(start 0.1524 0.127)
							(mid 0.137521 0.162921)
							(end 0.1016 0.1778)
						)
						(arc
							(start -0.1016 0.1778)
							(mid -0.137521 0.162921)
							(end -0.1524 0.127)
						)
						(arc
							(start -0.1524 -0.127)
							(mid -0.137521 -0.162921)
							(end -0.1016 -0.1778)
						)
						(arc
							(start 0.1016 -0.1778)
							(mid 0.137521 -0.162921)
							(end 0.1524 -0.127)
						)
					)
					(width 0)
					(fill yes)
				)
			)
		)
		(pad "2" smd custom
			(at 0 0.2794 90)
			(size 0.0762 0.0762)
			(layers "B.Cu" "B.Mask" "B.Paste")
			(net "GND")
			(options
				(clearance outline)
				(anchor circle)
			)
			(primitives
				(gr_poly
					(pts
						(arc
							(start 0.1524 0.127)
							(mid 0.137521 0.162921)
							(end 0.1016 0.1778)
						)
						(arc
							(start -0.1016 0.1778)
							(mid -0.137521 0.162921)
							(end -0.1524 0.127)
						)
						(arc
							(start -0.1524 -0.127)
							(mid -0.137521 -0.162921)
							(end -0.1016 -0.1778)
						)
						(arc
							(start 0.1016 -0.1778)
							(mid 0.137521 -0.162921)
							(end 0.1524 -0.127)
						)
					)
					(width 0)
					(fill yes)
				)
			)
		)
	)
	(footprint ""
		(layer "B.Cu")
		(at 176.890172 -35.637216)
		(property "Reference" "C414"
			(at 0 0 0)
			(layer "B.SilkS")
			(hide yes)
			(effects
				(font
					(size 1.27 1.27)
				)
				(justify mirror)
			)
		)
		(property "Value" "SC1U6D3V1MX-GP"
			(at -1.9177 2.0193 0)
			(unlocked yes)
			(layer "B.Fab")
			(hide yes)
			(effects
				(font
					(size 1.016 1.016)
					(thickness 0.1524)
				)
				(justify mirror)
			)
		)
		(property "Device Type" "C0201H14"
			(at -1.9177 0.4953 0)
			(unlocked yes)
			(layer "B.Fab")
			(hide yes)
			(effects
				(font
					(size 1.016 1.016)
					(thickness 0.1524)
				)
				(justify mirror)
			)
		)
		(duplicate_pad_numbers_are_jumpers no)
		(fp_rect
			(start 0.1524 0.3048)
			(end -0.1524 -0.3048)
			(stroke
				(width 0)
				(type default)
			)
			(fill no)
			(layer "B.CrtYd")
		)
		(fp_poly
			(pts
				(xy 0.2794 0.6477) (xy 0.2794 -0.6477) (xy -0.2794 -0.6477) (xy -0.2794 -0.1905) (xy -0.1524 -0.1905)
				(xy -0.1524 -0.3048) (xy 0.1524 -0.3048) (xy 0.1524 0.3048) (xy -0.1524 0.3048) (xy -0.1524 -0.1778)
				(xy -0.2794 -0.1778) (xy -0.2794 0.6477)
			)
			(stroke
				(width 0)
				(type default)
			)
			(fill no)
			(layer "B.CrtYd")
		)
		(fp_rect
			(start 0.2794 0.6477)
			(end -0.2794 -0.6477)
			(stroke
				(width 0)
				(type default)
			)
			(fill no)
			(layer "B.Fab")
		)
		(pad "1" smd custom
			(at 0 -0.2794 180)
			(size 0.0762 0.0762)
			(layers "B.Cu" "B.Mask" "B.Paste")
			(net "P0V975")
			(options
				(clearance outline)
				(anchor circle)
			)
			(primitives
				(gr_poly
					(pts
						(arc
							(start 0.1524 0.127)
							(mid 0.137521 0.162921)
							(end 0.1016 0.1778)
						)
						(arc
							(start -0.1016 0.1778)
							(mid -0.137521 0.162921)
							(end -0.1524 0.127)
						)
						(arc
							(start -0.1524 -0.127)
							(mid -0.137521 -0.162921)
							(end -0.1016 -0.1778)
						)
						(arc
							(start 0.1016 -0.1778)
							(mid 0.137521 -0.162921)
							(end 0.1524 -0.127)
						)
					)
					(width 0)
					(fill yes)
				)
			)
		)
		(pad "2" smd custom
			(at 0 0.2794 180)
			(size 0.0762 0.0762)
			(layers "B.Cu" "B.Mask" "B.Paste")
			(net "GND")
			(options
				(clearance outline)
				(anchor circle)
			)
			(primitives
				(gr_poly
					(pts
						(arc
							(start 0.1524 0.127)
							(mid 0.137521 0.162921)
							(end 0.1016 0.1778)
						)
						(arc
							(start -0.1016 0.1778)
							(mid -0.137521 0.162921)
							(end -0.1524 0.127)
						)
						(arc
							(start -0.1524 -0.127)
							(mid -0.137521 -0.162921)
							(end -0.1016 -0.1778)
						)
						(arc
							(start 0.1016 -0.1778)
							(mid 0.137521 -0.162921)
							(end 0.1524 -0.127)
						)
					)
					(width 0)
					(fill yes)
				)
			)
		)
	)
	(footprint ""
		(layer "B.Cu")
		(at 174.726092 -35.563048)
		(property "Reference" "C423"
			(at 0 0 0)
			(layer "B.SilkS")
			(hide yes)
			(effects
				(font
					(size 1.27 1.27)
				)
				(justify mirror)
			)
		)
		(property "Value" "SCD1U6D3V1KX-GP"
			(at 2.8321 -1.7399 0)
			(unlocked yes)
			(layer "B.Fab")
			(hide yes)
			(effects
				(font
					(size 1.016 1.016)
					(thickness 0.1524)
				)
				(justify mirror)
			)
		)
		(property "Device Type" "C0201H13"
			(at 2.8321 -3.2639 0)
			(unlocked yes)
			(layer "B.Fab")
			(hide yes)
			(effects
				(font
					(size 1.016 1.016)
					(thickness 0.1524)
				)
				(justify mirror)
			)
		)
		(duplicate_pad_numbers_are_jumpers no)
		(fp_rect
			(start 0.2794 0.6477)
			(end -0.2794 -0.6477)
			(stroke
				(width 0)
				(type default)
			)
			(fill no)
			(layer "B.CrtYd")
		)
		(fp_rect
			(start 0.2794 0.6477)
			(end -0.2794 -0.6477)
			(stroke
				(width 0)
				(type default)
			)
			(fill no)
			(layer "B.Fab")
		)
		(pad "1" smd custom
			(at 0 -0.2794 180)
			(size 0.0762 0.0762)
			(layers "B.Cu" "B.Mask" "B.Paste")
			(net "P0V975")
			(options
				(clearance outline)
				(anchor circle)
			)
			(primitives
				(gr_poly
					(pts
						(arc
							(start 0.1524 0.127)
							(mid 0.137521 0.162921)
							(end 0.1016 0.1778)
						)
						(arc
							(start -0.1016 0.1778)
							(mid -0.137521 0.162921)
							(end -0.1524 0.127)
						)
						(arc
							(start -0.1524 -0.127)
							(mid -0.137521 -0.162921)
							(end -0.1016 -0.1778)
						)
						(arc
							(start 0.1016 -0.1778)
							(mid 0.137521 -0.162921)
							(end 0.1524 -0.127)
						)
					)
					(width 0)
					(fill yes)
				)
			)
		)
		(pad "2" smd custom
			(at 0 0.2794 180)
			(size 0.0762 0.0762)
			(layers "B.Cu" "B.Mask" "B.Paste")
			(net "GND")
			(options
				(clearance outline)
				(anchor circle)
			)
			(primitives
				(gr_poly
					(pts
						(arc
							(start 0.1524 0.127)
							(mid 0.137521 0.162921)
							(end 0.1016 0.1778)
						)
						(arc
							(start -0.1016 0.1778)
							(mid -0.137521 0.162921)
							(end -0.1524 0.127)
						)
						(arc
							(start -0.1524 -0.127)
							(mid -0.137521 -0.162921)
							(end -0.1016 -0.1778)
						)
						(arc
							(start 0.1016 -0.1778)
							(mid 0.137521 -0.162921)
							(end 0.1524 -0.127)
						)
					)
					(width 0)
					(fill yes)
				)
			)
		)
	)
	(footprint ""
		(layer "B.Cu")
		(at 201.549 -27.051 -90)
		(property "Reference" "R283"
			(at 0 0 90)
			(layer "B.SilkS")
			(hide yes)
			(effects
				(font
					(size 1.27 1.27)
				)
				(justify mirror)
			)
		)
		(property "Value" "10R2F-L-GP"
			(at -0.064008 -3.993896 270)
			(unlocked yes)
			(layer "B.Fab")
			(hide yes)
			(effects
				(font
					(size 1.016 1.016)
					(thickness 0.1524)
				)
				(justify mirror)
			)
		)
		(property "Device Type" "R402H14"
			(at -0.064008 -5.517896 270)
			(unlocked yes)
			(layer "B.Fab")
			(hide yes)
			(effects
				(font
					(size 1.016 1.016)
					(thickness 0.1524)
				)
				(justify mirror)
			)
		)
		(duplicate_pad_numbers_are_jumpers no)
		(fp_line
			(start -0.508 -0.9398)
			(end 0.508 -0.9398)
			(stroke
				(width 0.1524)
				(type default)
			)
			(layer "B.SilkS")
		)
		(fp_line
			(start 0.508 -0.9398)
			(end 0.508 0.9398)
			(stroke
				(width 0.1524)
				(type default)
			)
			(layer "B.SilkS")
		)
		(fp_rect
			(start 0.508 0.9398)
			(end -0.508 -0.9398)
			(stroke
				(width 0)
				(type default)
			)
			(fill no)
			(layer "B.CrtYd")
		)
		(fp_rect
			(start 0.508 0.9398)
			(end -0.508 -0.9398)
			(stroke
				(width 0)
				(type default)
			)
			(fill no)
			(layer "B.Fab")
		)
		(pad "1" smd custom
			(at 0 -0.4445 90)
			(size 0.1397 0.1397)
			(layers "B.Cu" "B.Mask" "B.Paste")
			(net "P1V5_C")
			(options
				(clearance outline)
				(anchor circle)
			)
			(primitives
				(gr_poly
					(pts
						(arc
							(start -0.1778 0.2794)
							(mid -0.249642 0.249642)
							(end -0.2794 0.1778)
						)
						(arc
							(start -0.2794 -0.1778)
							(mid -0.249642 -0.249642)
							(end -0.1778 -0.2794)
						)
						(arc
							(start 0.1778 -0.2794)
							(mid 0.249642 -0.249642)
							(end 0.2794 -0.1778)
						)
						(arc
							(start 0.2794 0.1778)
							(mid 0.249642 0.249642)
							(end 0.1778 0.2794)
						)
					)
					(width 0)
					(fill yes)
				)
			)
		)
		(pad "2" smd custom
			(at 0 0.4445 90)
			(size 0.1397 0.1397)
			(layers "B.Cu" "B.Mask" "B.Paste")
			(net "PCE_VDDH")
			(options
				(clearance outline)
				(anchor circle)
			)
			(primitives
				(gr_poly
					(pts
						(arc
							(start -0.1778 0.2794)
							(mid -0.249642 0.249642)
							(end -0.2794 0.1778)
						)
						(arc
							(start -0.2794 -0.1778)
							(mid -0.249642 -0.249642)
							(end -0.1778 -0.2794)
						)
						(arc
							(start 0.1778 -0.2794)
							(mid 0.249642 -0.249642)
							(end 0.2794 -0.1778)
						)
						(arc
							(start 0.2794 0.1778)
							(mid 0.249642 0.249642)
							(end 0.1778 0.2794)
						)
					)
					(width 0)
					(fill yes)
				)
			)
		)
	)
	(footprint ""
		(layer "B.Cu")
		(at 124.9934 -39.4716 180)
		(property "Reference" "C52"
			(at 0 0 0)
			(layer "B.SilkS")
			(hide yes)
			(effects
				(font
					(size 1.27 1.27)
				)
				(justify mirror)
			)
		)
		(property "Value" "SCD01U16V1KX-GP"
			(at 2.8321 -1.7399 180)
			(unlocked yes)
			(layer "B.Fab")
			(hide yes)
			(effects
				(font
					(size 1.016 1.016)
					(thickness 0.1524)
				)
				(justify mirror)
			)
		)
		(property "Device Type" "C0201H13"
			(at 2.8321 -3.2639 180)
			(unlocked yes)
			(layer "B.Fab")
			(hide yes)
			(effects
				(font
					(size 1.016 1.016)
					(thickness 0.1524)
				)
				(justify mirror)
			)
		)
		(duplicate_pad_numbers_are_jumpers no)
		(fp_rect
			(start 0.2794 0.6477)
			(end -0.2794 -0.6477)
			(stroke
				(width 0)
				(type default)
			)
			(fill no)
			(layer "B.CrtYd")
		)
		(fp_rect
			(start 0.2794 0.6477)
			(end -0.2794 -0.6477)
			(stroke
				(width 0)
				(type default)
			)
			(fill no)
			(layer "B.Fab")
		)
		(pad "1" smd custom
			(at 0 -0.2794)
			(size 0.0762 0.0762)
			(layers "B.Cu" "B.Mask" "B.Paste")
			(net "PHY_DPB_TO_SCC_38_DN")
			(options
				(clearance outline)
				(anchor circle)
			)
			(primitives
				(gr_poly
					(pts
						(arc
							(start 0.1524 0.127)
							(mid 0.137521 0.162921)
							(end 0.1016 0.1778)
						)
						(arc
							(start -0.1016 0.1778)
							(mid -0.137521 0.162921)
							(end -0.1524 0.127)
						)
						(arc
							(start -0.1524 -0.127)
							(mid -0.137521 -0.162921)
							(end -0.1016 -0.1778)
						)
						(arc
							(start 0.1016 -0.1778)
							(mid 0.137521 -0.162921)
							(end 0.1524 -0.127)
						)
					)
					(width 0)
					(fill yes)
				)
			)
		)
		(pad "2" smd custom
			(at 0 0.2794)
			(size 0.0762 0.0762)
			(layers "B.Cu" "B.Mask" "B.Paste")
			(net "PHY_DPB_TO_SCC_C_38_DN")
			(options
				(clearance outline)
				(anchor circle)
			)
			(primitives
				(gr_poly
					(pts
						(arc
							(start 0.1524 0.127)
							(mid 0.137521 0.162921)
							(end 0.1016 0.1778)
						)
						(arc
							(start -0.1016 0.1778)
							(mid -0.137521 0.162921)
							(end -0.1524 0.127)
						)
						(arc
							(start -0.1524 -0.127)
							(mid -0.137521 -0.162921)
							(end -0.1016 -0.1778)
						)
						(arc
							(start 0.1016 -0.1778)
							(mid 0.137521 -0.162921)
							(end 0.1524 -0.127)
						)
					)
					(width 0)
					(fill yes)
				)
			)
		)
	)
	(footprint ""
		(layer "B.Cu")
		(at 135.622538 -84.709)
		(property "Reference" "R59"
			(at 0 0 0)
			(layer "B.SilkS")
			(hide yes)
			(effects
				(font
					(size 1.27 1.27)
				)
				(justify mirror)
			)
		)
		(property "Value" "4K7R2F-GP"
			(at -0.064008 -3.993896 0)
			(unlocked yes)
			(layer "B.Fab")
			(hide yes)
			(effects
				(font
					(size 1.016 1.016)
					(thickness 0.1524)
				)
				(justify mirror)
			)
		)
		(property "Device Type" "R402H16"
			(at -0.064008 -5.517896 0)
			(unlocked yes)
			(layer "B.Fab")
			(hide yes)
			(effects
				(font
					(size 1.016 1.016)
					(thickness 0.1524)
				)
				(justify mirror)
			)
		)
		(duplicate_pad_numbers_are_jumpers no)
		(fp_line
			(start -0.508 -0.9398)
			(end 0.508 -0.9398)
			(stroke
				(width 0.1524)
				(type default)
			)
			(layer "B.SilkS")
		)
		(fp_line
			(start 0.508 -0.9398)
			(end 0.508 0.9398)
			(stroke
				(width 0.1524)
				(type default)
			)
			(layer "B.SilkS")
		)
		(fp_rect
			(start 0.508 0.9398)
			(end -0.508 -0.9398)
			(stroke
				(width 0)
				(type default)
			)
			(fill no)
			(layer "B.CrtYd")
		)
		(fp_rect
			(start 0.508 0.9398)
			(end -0.508 -0.9398)
			(stroke
				(width 0)
				(type default)
			)
			(fill no)
			(layer "B.Fab")
		)
		(pad "1" smd custom
			(at 0 -0.4445 180)
			(size 0.1397 0.1397)
			(layers "B.Cu" "B.Mask" "B.Paste")
			(net "P1V8_E")
			(options
				(clearance outline)
				(anchor circle)
			)
			(primitives
				(gr_poly
					(pts
						(arc
							(start -0.1778 0.2794)
							(mid -0.249642 0.249642)
							(end -0.2794 0.1778)
						)
						(arc
							(start -0.2794 -0.1778)
							(mid -0.249642 -0.249642)
							(end -0.1778 -0.2794)
						)
						(arc
							(start 0.1778 -0.2794)
							(mid 0.249642 -0.249642)
							(end 0.2794 -0.1778)
						)
						(arc
							(start 0.2794 0.1778)
							(mid 0.249642 0.249642)
							(end 0.1778 0.2794)
						)
					)
					(width 0)
					(fill yes)
				)
			)
		)
		(pad "2" smd custom
			(at 0 0.4445 180)
			(size 0.1397 0.1397)
			(layers "B.Cu" "B.Mask" "B.Paste")
			(net "I2C_DRIVE_INS_SDA5_LS")
			(options
				(clearance outline)
				(anchor circle)
			)
			(primitives
				(gr_poly
					(pts
						(arc
							(start -0.1778 0.2794)
							(mid -0.249642 0.249642)
							(end -0.2794 0.1778)
						)
						(arc
							(start -0.2794 -0.1778)
							(mid -0.249642 -0.249642)
							(end -0.1778 -0.2794)
						)
						(arc
							(start 0.1778 -0.2794)
							(mid 0.249642 -0.249642)
							(end 0.2794 -0.1778)
						)
						(arc
							(start 0.2794 0.1778)
							(mid 0.249642 0.249642)
							(end 0.1778 0.2794)
						)
					)
					(width 0)
					(fill yes)
				)
			)
		)
	)
)
